FILE_TYPE = MULTI_PHYS_TABLE;
PART 'RT8240'
{=========================================================================================================================================================================================}
:PACK_TYPE | MATERIAL | PART_NUMBER     = EnvComp | PART_NUMBER  | JEDEC_TYPE     | DESCRIPTION                  | CLASS | COMPONENT_TYPE | HEIGHT      | LPID     | SPEED_URL | Status |RPL| AML | Bus_Unit | Days ;
{=========================================================================================================================================================================================}
'QFN'      | 'IC'     | 'H66262-001'(!) = ''      | 'H66262-001' | 'QFN12_8_4MA'  | 'IC,LIN,WQFN,RT8240C,VREG'   | 'IC'  | 'LCC'          | '0.031 IN'  | '3810'   | 'http://speed.intel.com:8081/speed/module/pdm/item/pdm_item_detail_direct.asp?item_cde=H66262-001&item_rev=01&url_param=unused' | '' | '' | '' | '' | '' 
'QFN'      | 'EMPTY'  | 'H66262-001'(!) = ''      | 'H66262-001' | 'QFN12_8_4MA'  | 'IC,LIN,WQFN,RT8240C,VREG'   | 'IO'  | 'LCC'          | '0.031 IN'  | '3810'   | 'http://speed.intel.com:8081/speed/module/pdm/item/pdm_item_detail_direct.asp?item_cde=H66262-001&item_rev=01&url_param=unused' | '' | '' | '' | '' | '' 
END_PART
END.
